(kicad_pcb
	(version 20260206)
	(generator "pcbnew")
	(generator_version "10.0")
	(general
		(thickness 1.6)
		(legacy_teardrops no)
	)
	(paper "A4")
	(title_block
		(title "panther-plus-userver — 13130-1b_20150205.brd")
		(comment 1 "Honey Badger (Wiwynn) / footprints 612-619 of 1509")
	)
	(layers
		(0 "F.Cu" signal "TOP")
		(4 "In1.Cu" signal "L2")
		(6 "In2.Cu" signal "L3")
		(8 "In3.Cu" signal "L4")
		(10 "In4.Cu" signal "L5")
		(12 "In5.Cu" signal "L6")
		(14 "In6.Cu" signal "L7")
		(16 "In7.Cu" signal "L8")
		(18 "In8.Cu" signal "L9")
		(20 "In9.Cu" signal "L10")
		(22 "In10.Cu" signal "L11")
		(2 "B.Cu" signal "BOTTOM")
		(9 "F.Adhes" user "F.Adhesive")
		(11 "B.Adhes" user "B.Adhesive")
		(13 "F.Paste" user "Package Geometry/Pastemask Top")
		(15 "B.Paste" user "Package Geometry/Pastemask Bottom")
		(5 "F.SilkS" user "Ref Des/Silkscreen Top")
		(7 "B.SilkS" user "Ref Des/Silkscreen Bottom")
		(1 "F.Mask" user "Board Geometry/Soldermask Top")
		(3 "B.Mask" user "Board Geometry/Soldermask Bottom")
		(17 "Dwgs.User" user "User.Drawings")
		(19 "Cmts.User" user "User.Comments")
		(21 "Eco1.User" user "User.Eco1")
		(23 "Eco2.User" user "User.Eco2")
		(25 "Edge.Cuts" user "Board Geometry/Outline")
		(27 "Margin" user)
		(31 "F.CrtYd" user "Package Geometry/Place Bound Top")
		(29 "B.CrtYd" user "Package Geometry/Place Bound Bottom")
		(35 "F.Fab" user "Ref Des/Assembly Top")
		(33 "B.Fab" user "Ref Des/Assembly Bottom")
	)
	(footprint ""
		(layer "F.Cu")
		(at 74.168 -42.418 90)
		(property "Reference" "R72"
			(at 0 0 90)
			(layer "F.SilkS")
			(hide yes)
			(effects
				(font
					(size 1.27 1.27)
				)
			)
		)
		(property "Value" "4K7R2F-GP"
			(at 0.064008 -3.993896 90)
			(unlocked yes)
			(layer "F.Fab")
			(hide yes)
			(effects
				(font
					(size 1.016 1.016)
					(thickness 0.1524)
				)
			)
		)
		(property "Device Type" "R402H16"
			(at 0.064008 -5.517896 90)
			(unlocked yes)
			(layer "F.Fab")
			(hide yes)
			(effects
				(font
					(size 1.016 1.016)
					(thickness 0.1524)
				)
			)
		)
		(duplicate_pad_numbers_are_jumpers no)
		(fp_rect
			(start -0.381 0.8382)
			(end 0.381 -0.8382)
			(stroke
				(width 0)
				(type default)
			)
			(fill no)
			(layer "F.CrtYd")
		)
		(fp_rect
			(start -0.381 0.8382)
			(end 0.381 -0.8382)
			(stroke
				(width 0)
				(type default)
			)
			(fill no)
			(layer "F.Fab")
		)
		(pad "1" smd custom
			(at 0 -0.4318 90)
			(size 0.127 0.127)
			(layers "F.Cu" "F.Mask" "F.Paste")
			(net "P3V3")
			(options
				(clearance outline)
				(anchor circle)
			)
			(primitives
				(gr_poly
					(pts
						(arc
							(start -0.2032 -0.2794)
							(mid -0.239121 -0.264521)
							(end -0.254 -0.2286)
						)
						(arc
							(start -0.254 0.2286)
							(mid -0.239121 0.264521)
							(end -0.2032 0.2794)
						)
						(arc
							(start 0.2032 0.2794)
							(mid 0.239121 0.264521)
							(end 0.254 0.2286)
						)
						(arc
							(start 0.254 -0.2286)
							(mid 0.239121 -0.264521)
							(end 0.2032 -0.2794)
						)
					)
					(width 0)
					(fill yes)
				)
			)
		)
		(pad "2" smd custom
			(at 0 0.4318 90)
			(size 0.127 0.127)
			(layers "F.Cu" "F.Mask" "F.Paste")
			(net "CPU_ERR_N2")
			(options
				(clearance outline)
				(anchor circle)
			)
			(primitives
				(gr_poly
					(pts
						(arc
							(start -0.2032 -0.2794)
							(mid -0.239121 -0.264521)
							(end -0.254 -0.2286)
						)
						(arc
							(start -0.254 0.2286)
							(mid -0.239121 0.264521)
							(end -0.2032 0.2794)
						)
						(arc
							(start 0.2032 0.2794)
							(mid 0.239121 0.264521)
							(end 0.254 0.2286)
						)
						(arc
							(start 0.254 -0.2286)
							(mid 0.239121 -0.264521)
							(end 0.2032 -0.2794)
						)
					)
					(width 0)
					(fill yes)
				)
			)
		)
	)
	(footprint ""
		(layer "F.Cu")
		(at 27.5717 -36.576)
		(property "Reference" "PR200"
			(at 0 0 0)
			(layer "F.SilkS")
			(hide yes)
			(effects
				(font
					(size 1.27 1.27)
				)
			)
		)
		(property "Value" "10R3F-GP"
			(at -0.0254 -2.0193 0)
			(unlocked yes)
			(layer "F.Fab")
			(hide yes)
			(effects
				(font
					(size 1.016 1.016)
					(thickness 0.1524)
				)
			)
		)
		(property "Device Type" "R603H22"
			(at -0.0254 -3.5433 0)
			(unlocked yes)
			(layer "F.Fab")
			(hide yes)
			(effects
				(font
					(size 1.016 1.016)
					(thickness 0.1524)
				)
			)
		)
		(duplicate_pad_numbers_are_jumpers no)
		(fp_line
			(start -0.2032 0)
			(end -0.4191 0)
			(stroke
				(width 0.2032)
				(type default)
			)
			(layer "F.SilkS")
		)
		(fp_line
			(start 0.4318 0)
			(end 0.2032 0)
			(stroke
				(width 0.2032)
				(type default)
			)
			(layer "F.SilkS")
		)
		(fp_rect
			(start -0.635 1.1811)
			(end 0.635 -1.1811)
			(stroke
				(width 0)
				(type default)
			)
			(fill no)
			(layer "F.CrtYd")
		)
		(fp_rect
			(start -0.635 1.1811)
			(end 0.635 -1.1811)
			(stroke
				(width 0)
				(type default)
			)
			(fill no)
			(layer "F.Fab")
		)
		(pad "1" smd custom
			(at 0 -0.6604)
			(size 0.19685 0.19685)
			(layers "F.Cu" "F.Mask" "F.Paste")
			(net "P3V3_STBY_OUT")
			(options
				(clearance outline)
				(anchor circle)
			)
			(primitives
				(gr_poly
					(pts
						(arc
							(start 0.508 -0.2921)
							(mid 0.478242 -0.363942)
							(end 0.4064 -0.3937)
						)
						(arc
							(start -0.4064 -0.3937)
							(mid -0.478242 -0.363942)
							(end -0.508 -0.2921)
						)
						(arc
							(start -0.508 0.2921)
							(mid -0.478242 0.363942)
							(end -0.4064 0.3937)
						)
						(arc
							(start 0.4064 0.3937)
							(mid 0.478242 0.363942)
							(end 0.508 0.2921)
						)
					)
					(width 0)
					(fill yes)
				)
			)
		)
		(pad "2" smd custom
			(at 0 0.6604)
			(size 0.19685 0.19685)
			(layers "F.Cu" "F.Mask" "F.Paste")
			(net "P3V3_STBY_VFB_R")
			(options
				(clearance outline)
				(anchor circle)
			)
			(primitives
				(gr_poly
					(pts
						(arc
							(start 0.508 -0.2921)
							(mid 0.478242 -0.363942)
							(end 0.4064 -0.3937)
						)
						(arc
							(start -0.4064 -0.3937)
							(mid -0.478242 -0.363942)
							(end -0.508 -0.2921)
						)
						(arc
							(start -0.508 0.2921)
							(mid -0.478242 0.363942)
							(end -0.4064 0.3937)
						)
						(arc
							(start 0.4064 0.3937)
							(mid 0.478242 0.363942)
							(end 0.508 0.2921)
						)
					)
					(width 0)
					(fill yes)
				)
			)
		)
	)
	(footprint ""
		(layer "F.Cu")
		(at 56.007 -34.544 -90)
		(property "Reference" "R116"
			(at 0 0 270)
			(layer "F.SilkS")
			(hide yes)
			(effects
				(font
					(size 1.27 1.27)
				)
			)
		)
		(property "Value" "2K2R2F-GP"
			(at 0.064008 -3.993896 270)
			(unlocked yes)
			(layer "F.Fab")
			(hide yes)
			(effects
				(font
					(size 1.016 1.016)
					(thickness 0.1524)
				)
			)
		)
		(property "Device Type" "R402H16"
			(at 0.064008 -5.517896 270)
			(unlocked yes)
			(layer "F.Fab")
			(hide yes)
			(effects
				(font
					(size 1.016 1.016)
					(thickness 0.1524)
				)
			)
		)
		(duplicate_pad_numbers_are_jumpers no)
		(fp_rect
			(start -0.381 0.8382)
			(end 0.381 -0.8382)
			(stroke
				(width 0)
				(type default)
			)
			(fill no)
			(layer "F.CrtYd")
		)
		(fp_rect
			(start -0.381 0.8382)
			(end 0.381 -0.8382)
			(stroke
				(width 0)
				(type default)
			)
			(fill no)
			(layer "F.Fab")
		)
		(pad "1" smd custom
			(at 0 -0.4318 270)
			(size 0.127 0.127)
			(layers "F.Cu" "F.Mask" "F.Paste")
			(net "P3V3_CPU")
			(options
				(clearance outline)
				(anchor circle)
			)
			(primitives
				(gr_poly
					(pts
						(arc
							(start -0.2032 -0.2794)
							(mid -0.239121 -0.264521)
							(end -0.254 -0.2286)
						)
						(arc
							(start -0.254 0.2286)
							(mid -0.239121 0.264521)
							(end -0.2032 0.2794)
						)
						(arc
							(start 0.2032 0.2794)
							(mid 0.239121 0.264521)
							(end 0.254 0.2286)
						)
						(arc
							(start 0.254 -0.2286)
							(mid 0.239121 -0.264521)
							(end 0.2032 -0.2794)
						)
					)
					(width 0)
					(fill yes)
				)
			)
		)
		(pad "2" smd custom
			(at 0 0.4318 270)
			(size 0.127 0.127)
			(layers "F.Cu" "F.Mask" "F.Paste")
			(net "SPI_WP_R_N_1")
			(options
				(clearance outline)
				(anchor circle)
			)
			(primitives
				(gr_poly
					(pts
						(arc
							(start -0.2032 -0.2794)
							(mid -0.239121 -0.264521)
							(end -0.254 -0.2286)
						)
						(arc
							(start -0.254 0.2286)
							(mid -0.239121 0.264521)
							(end -0.2032 0.2794)
						)
						(arc
							(start 0.2032 0.2794)
							(mid 0.239121 0.264521)
							(end 0.254 0.2286)
						)
						(arc
							(start 0.254 -0.2286)
							(mid 0.239121 -0.264521)
							(end 0.2032 -0.2794)
						)
					)
					(width 0)
					(fill yes)
				)
			)
		)
	)
	(footprint ""
		(layer "F.Cu")
		(at 143.891 -21.082 180)
		(property "Reference" "R89"
			(at 0 0 180)
			(layer "F.SilkS")
			(hide yes)
			(effects
				(font
					(size 1.27 1.27)
				)
			)
		)
		(property "Value" "300R2F-GP"
			(at 0.064008 -3.993896 180)
			(unlocked yes)
			(layer "F.Fab")
			(hide yes)
			(effects
				(font
					(size 1.016 1.016)
					(thickness 0.1524)
				)
			)
		)
		(property "Device Type" "R402H16"
			(at 0.064008 -5.517896 180)
			(unlocked yes)
			(layer "F.Fab")
			(hide yes)
			(effects
				(font
					(size 1.016 1.016)
					(thickness 0.1524)
				)
			)
		)
		(duplicate_pad_numbers_are_jumpers no)
		(fp_rect
			(start -0.381 0.8382)
			(end 0.381 -0.8382)
			(stroke
				(width 0)
				(type default)
			)
			(fill no)
			(layer "F.CrtYd")
		)
		(fp_rect
			(start -0.381 0.8382)
			(end 0.381 -0.8382)
			(stroke
				(width 0)
				(type default)
			)
			(fill no)
			(layer "F.Fab")
		)
		(pad "1" smd custom
			(at 0 -0.4318 180)
			(size 0.127 0.127)
			(layers "F.Cu" "F.Mask" "F.Paste")
			(net "C_CONF_DONE")
			(options
				(clearance outline)
				(anchor circle)
			)
			(primitives
				(gr_poly
					(pts
						(arc
							(start -0.2032 -0.2794)
							(mid -0.239121 -0.264521)
							(end -0.254 -0.2286)
						)
						(arc
							(start -0.254 0.2286)
							(mid -0.239121 0.264521)
							(end -0.2032 0.2794)
						)
						(arc
							(start 0.2032 0.2794)
							(mid 0.239121 0.264521)
							(end 0.254 0.2286)
						)
						(arc
							(start 0.254 -0.2286)
							(mid 0.239121 -0.264521)
							(end 0.2032 -0.2794)
						)
					)
					(width 0)
					(fill yes)
				)
			)
		)
		(pad "2" smd custom
			(at 0 0.4318 180)
			(size 0.127 0.127)
			(layers "F.Cu" "F.Mask" "F.Paste")
			(net "P3V3_STBY")
			(options
				(clearance outline)
				(anchor circle)
			)
			(primitives
				(gr_poly
					(pts
						(arc
							(start -0.2032 -0.2794)
							(mid -0.239121 -0.264521)
							(end -0.254 -0.2286)
						)
						(arc
							(start -0.254 0.2286)
							(mid -0.239121 0.264521)
							(end -0.2032 0.2794)
						)
						(arc
							(start 0.2032 0.2794)
							(mid 0.239121 0.264521)
							(end 0.254 0.2286)
						)
						(arc
							(start 0.254 -0.2286)
							(mid 0.239121 -0.264521)
							(end 0.2032 -0.2794)
						)
					)
					(width 0)
					(fill yes)
				)
			)
		)
	)
	(footprint ""
		(layer "F.Cu")
		(at 17.4752 -34.544 180)
		(property "Reference" "PC164"
			(at 0 0 180)
			(layer "F.SilkS")
			(hide yes)
			(effects
				(font
					(size 1.27 1.27)
				)
			)
		)
		(property "Value" "SCD1U50V3KX-GP"
			(at -0.0254 -2.0193 180)
			(unlocked yes)
			(layer "F.Fab")
			(hide yes)
			(effects
				(font
					(size 1.016 1.016)
					(thickness 0.1524)
				)
			)
		)
		(property "Device Type" "C603H36"
			(at -0.0254 -3.5433 180)
			(unlocked yes)
			(layer "F.Fab")
			(hide yes)
			(effects
				(font
					(size 1.016 1.016)
					(thickness 0.1524)
				)
			)
		)
		(duplicate_pad_numbers_are_jumpers no)
		(fp_line
			(start -0.4064 0)
			(end 0.4064 0)
			(stroke
				(width 0.2286)
				(type default)
			)
			(layer "F.SilkS")
		)
		(fp_rect
			(start -0.635 1.1811)
			(end 0.635 -1.1811)
			(stroke
				(width 0)
				(type default)
			)
			(fill no)
			(layer "F.CrtYd")
		)
		(fp_rect
			(start -0.635 1.1811)
			(end 0.635 -1.1811)
			(stroke
				(width 0)
				(type default)
			)
			(fill no)
			(layer "F.Fab")
		)
		(pad "1" smd custom
			(at 0 -0.6604 180)
			(size 0.19685 0.19685)
			(layers "F.Cu" "F.Mask" "F.Paste")
			(net "P3V3_STBY_VBST_RC")
			(options
				(clearance outline)
				(anchor circle)
			)
			(primitives
				(gr_poly
					(pts
						(arc
							(start 0.508 -0.2921)
							(mid 0.478242 -0.363942)
							(end 0.4064 -0.3937)
						)
						(arc
							(start -0.4064 -0.3937)
							(mid -0.478242 -0.363942)
							(end -0.508 -0.2921)
						)
						(arc
							(start -0.508 0.2921)
							(mid -0.478242 0.363942)
							(end -0.4064 0.3937)
						)
						(arc
							(start 0.4064 0.3937)
							(mid 0.478242 0.363942)
							(end 0.508 0.2921)
						)
					)
					(width 0)
					(fill yes)
				)
			)
		)
		(pad "2" smd custom
			(at 0 0.6604 180)
			(size 0.19685 0.19685)
			(layers "F.Cu" "F.Mask" "F.Paste")
			(net "P3V3_STBY_LL")
			(options
				(clearance outline)
				(anchor circle)
			)
			(primitives
				(gr_poly
					(pts
						(arc
							(start 0.508 -0.2921)
							(mid 0.478242 -0.363942)
							(end 0.4064 -0.3937)
						)
						(arc
							(start -0.4064 -0.3937)
							(mid -0.478242 -0.363942)
							(end -0.508 -0.2921)
						)
						(arc
							(start -0.508 0.2921)
							(mid -0.478242 0.363942)
							(end -0.4064 0.3937)
						)
						(arc
							(start 0.4064 0.3937)
							(mid 0.478242 0.363942)
							(end 0.508 0.2921)
						)
					)
					(width 0)
					(fill yes)
				)
			)
		)
	)
	(footprint ""
		(layer "F.Cu")
		(at 64.77 -47.371 -90)
		(property "Reference" "R40"
			(at 0 0 270)
			(layer "F.SilkS")
			(hide yes)
			(effects
				(font
					(size 1.27 1.27)
				)
			)
		)
		(property "Value" "0R2J-2-GP"
			(at 0.064008 -3.993896 270)
			(unlocked yes)
			(layer "F.Fab")
			(hide yes)
			(effects
				(font
					(size 1.016 1.016)
					(thickness 0.1524)
				)
			)
		)
		(property "Device Type" "R402H16"
			(at 0.064008 -5.517896 270)
			(unlocked yes)
			(layer "F.Fab")
			(hide yes)
			(effects
				(font
					(size 1.016 1.016)
					(thickness 0.1524)
				)
			)
		)
		(duplicate_pad_numbers_are_jumpers no)
		(fp_rect
			(start -0.381 0.8382)
			(end 0.381 -0.8382)
			(stroke
				(width 0)
				(type default)
			)
			(fill no)
			(layer "F.CrtYd")
		)
		(fp_rect
			(start -0.381 0.8382)
			(end 0.381 -0.8382)
			(stroke
				(width 0)
				(type default)
			)
			(fill no)
			(layer "F.Fab")
		)
		(pad "1" smd custom
			(at 0 -0.4318 270)
			(size 0.127 0.127)
			(layers "F.Cu" "F.Mask" "F.Paste")
			(net "SMB_HOST_LV_R_DATA")
			(options
				(clearance outline)
				(anchor circle)
			)
			(primitives
				(gr_poly
					(pts
						(arc
							(start -0.2032 -0.2794)
							(mid -0.239121 -0.264521)
							(end -0.254 -0.2286)
						)
						(arc
							(start -0.254 0.2286)
							(mid -0.239121 0.264521)
							(end -0.2032 0.2794)
						)
						(arc
							(start 0.2032 0.2794)
							(mid 0.239121 0.264521)
							(end 0.254 0.2286)
						)
						(arc
							(start 0.254 -0.2286)
							(mid 0.239121 -0.264521)
							(end 0.2032 -0.2794)
						)
					)
					(width 0)
					(fill yes)
				)
			)
		)
		(pad "2" smd custom
			(at 0 0.4318 270)
			(size 0.127 0.127)
			(layers "F.Cu" "F.Mask" "F.Paste")
			(net "SMB_HOST_LV_DATA")
			(options
				(clearance outline)
				(anchor circle)
			)
			(primitives
				(gr_poly
					(pts
						(arc
							(start -0.2032 -0.2794)
							(mid -0.239121 -0.264521)
							(end -0.254 -0.2286)
						)
						(arc
							(start -0.254 0.2286)
							(mid -0.239121 0.264521)
							(end -0.2032 0.2794)
						)
						(arc
							(start 0.2032 0.2794)
							(mid 0.239121 0.264521)
							(end 0.254 0.2286)
						)
						(arc
							(start 0.254 -0.2286)
							(mid 0.239121 -0.264521)
							(end 0.2032 -0.2794)
						)
					)
					(width 0)
					(fill yes)
				)
			)
		)
	)
	(footprint ""
		(layer "F.Cu")
		(at 118.237 -64.389 180)
		(property "Reference" "R226"
			(at 0 0 180)
			(layer "F.SilkS")
			(hide yes)
			(effects
				(font
					(size 1.27 1.27)
				)
			)
		)
		(property "Value" "0R2J-2-GP"
			(at 0.064008 -3.993896 180)
			(unlocked yes)
			(layer "F.Fab")
			(hide yes)
			(effects
				(font
					(size 1.016 1.016)
					(thickness 0.1524)
				)
			)
		)
		(property "Device Type" "R402H16"
			(at 0.064008 -5.517896 180)
			(unlocked yes)
			(layer "F.Fab")
			(hide yes)
			(effects
				(font
					(size 1.016 1.016)
					(thickness 0.1524)
				)
			)
		)
		(duplicate_pad_numbers_are_jumpers no)
		(fp_rect
			(start -0.381 0.8382)
			(end 0.381 -0.8382)
			(stroke
				(width 0)
				(type default)
			)
			(fill no)
			(layer "F.CrtYd")
		)
		(fp_rect
			(start -0.381 0.8382)
			(end 0.381 -0.8382)
			(stroke
				(width 0)
				(type default)
			)
			(fill no)
			(layer "F.Fab")
		)
		(pad "1" smd custom
			(at 0 -0.4318 180)
			(size 0.127 0.127)
			(layers "F.Cu" "F.Mask" "F.Paste")
			(net "SMB_M_A1_R_CLK")
			(options
				(clearance outline)
				(anchor circle)
			)
			(primitives
				(gr_poly
					(pts
						(arc
							(start -0.2032 -0.2794)
							(mid -0.239121 -0.264521)
							(end -0.254 -0.2286)
						)
						(arc
							(start -0.254 0.2286)
							(mid -0.239121 0.264521)
							(end -0.2032 0.2794)
						)
						(arc
							(start 0.2032 0.2794)
							(mid 0.239121 0.264521)
							(end 0.254 0.2286)
						)
						(arc
							(start 0.254 -0.2286)
							(mid 0.239121 -0.264521)
							(end 0.2032 -0.2794)
						)
					)
					(width 0)
					(fill yes)
				)
			)
		)
		(pad "2" smd custom
			(at 0 0.4318 180)
			(size 0.127 0.127)
			(layers "F.Cu" "F.Mask" "F.Paste")
			(net "SMB_HOST_LV_CLK")
			(options
				(clearance outline)
				(anchor circle)
			)
			(primitives
				(gr_poly
					(pts
						(arc
							(start -0.2032 -0.2794)
							(mid -0.239121 -0.264521)
							(end -0.254 -0.2286)
						)
						(arc
							(start -0.254 0.2286)
							(mid -0.239121 0.264521)
							(end -0.2032 0.2794)
						)
						(arc
							(start 0.2032 0.2794)
							(mid 0.239121 0.264521)
							(end 0.254 0.2286)
						)
						(arc
							(start 0.254 -0.2286)
							(mid 0.239121 -0.264521)
							(end 0.2032 -0.2794)
						)
					)
					(width 0)
					(fill yes)
				)
			)
		)
	)
	(footprint ""
		(layer "F.Cu")
		(at 181.61 -36.068)
		(property "Reference" "PR134"
			(at 0 0 0)
			(layer "F.SilkS")
			(hide yes)
			(effects
				(font
					(size 1.27 1.27)
				)
			)
		)
		(property "Value" "0R2J-2-GP"
			(at 0.064008 -3.993896 0)
			(unlocked yes)
			(layer "F.Fab")
			(hide yes)
			(effects
				(font
					(size 1.016 1.016)
					(thickness 0.1524)
				)
			)
		)
		(property "Device Type" "R402H16"
			(at 0.064008 -5.517896 0)
			(unlocked yes)
			(layer "F.Fab")
			(hide yes)
			(effects
				(font
					(size 1.016 1.016)
					(thickness 0.1524)
				)
			)
		)
		(duplicate_pad_numbers_are_jumpers no)
		(fp_rect
			(start -0.381 0.8382)
			(end 0.381 -0.8382)
			(stroke
				(width 0)
				(type default)
			)
			(fill no)
			(layer "F.CrtYd")
		)
		(fp_rect
			(start -0.381 0.8382)
			(end 0.381 -0.8382)
			(stroke
				(width 0)
				(type default)
			)
			(fill no)
			(layer "F.Fab")
		)
		(pad "1" smd custom
			(at 0 -0.4318)
			(size 0.127 0.127)
			(layers "F.Cu" "F.Mask" "F.Paste")
			(net "VR_PWREN_PVDDR_A")
			(options
				(clearance outline)
				(anchor circle)
			)
			(primitives
				(gr_poly
					(pts
						(arc
							(start -0.2032 -0.2794)
							(mid -0.239121 -0.264521)
							(end -0.254 -0.2286)
						)
						(arc
							(start -0.254 0.2286)
							(mid -0.239121 0.264521)
							(end -0.2032 0.2794)
						)
						(arc
							(start 0.2032 0.2794)
							(mid 0.239121 0.264521)
							(end 0.254 0.2286)
						)
						(arc
							(start 0.254 -0.2286)
							(mid 0.239121 -0.264521)
							(end 0.2032 -0.2794)
						)
					)
					(width 0)
					(fill yes)
				)
			)
		)
		(pad "2" smd custom
			(at 0 0.4318)
			(size 0.127 0.127)
			(layers "F.Cu" "F.Mask" "F.Paste")
			(net "PMU_SLP_S45#")
			(options
				(clearance outline)
				(anchor circle)
			)
			(primitives
				(gr_poly
					(pts
						(arc
							(start -0.2032 -0.2794)
							(mid -0.239121 -0.264521)
							(end -0.254 -0.2286)
						)
						(arc
							(start -0.254 0.2286)
							(mid -0.239121 0.264521)
							(end -0.2032 0.2794)
						)
						(arc
							(start 0.2032 0.2794)
							(mid 0.239121 0.264521)
							(end 0.254 0.2286)
						)
						(arc
							(start 0.254 -0.2286)
							(mid 0.239121 -0.264521)
							(end 0.2032 -0.2794)
						)
					)
					(width 0)
					(fill yes)
				)
			)
		)
	)
)
